# BASEBOARD_FAB2 (Tioga Pass) — schematic netlist excerpt (pin names and nets, part order shuffled) for the footprints in the layout excerpt that follows; sources: Cadence DE-HDL packaged netlist, KiCad conversion of Wiwynn_Tioga_Pass_MB.brd

J9M1  SCONN288_H44441003  SCONN  pkg PIP  page 84
  \12v\(1)  = P12V_NVDIMM_KLM
  VSS(93)  = GND
  DQ(4)  = M_K_DQ<4>
  VSS(92)  = GND
  DQ(0)  = M_K_DQ<0>
  VSS(91)  = GND
  DQS9P  = M_K_DQS_DP<9>
  DQS9N  = M_K_DQS_DN<9>
  VSS(90)  = GND
  DQ(6)  = M_K_DQ<6>
  VSS(89)  = GND
  DQ(2)  = M_K_DQ<2>
  VSS(88)  = GND
  DQ(12)  = M_K_DQ<12>
  VSS(87)  = GND
  DQ(8)  = M_K_DQ<8>
  VSS(86)  = GND
  DQS10P  = M_K_DQS_DP<10>
  DQS10N  = M_K_DQS_DN<10>
  VSS(85)  = GND
  DQ(14)  = M_K_DQ<14>
  VSS(84)  = GND
  DQ(10)  = M_K_DQ<10>
  VSS(83)  = GND
  DQ(20)  = M_K_DQ<20>
  VSS(82)  = GND
  DQ(16)  = M_K_DQ<16>
  VSS(81)  = GND
  DQS11P  = M_K_DQS_DP<11>
  DQS11N  = M_K_DQS_DN<11>
  VSS(80)  = GND
  DQ(22)  = M_K_DQ<22>
  VSS(79)  = GND
  DQ(18)  = M_K_DQ<18>
  VSS(78)  = GND
  DQ(28)  = M_K_DQ<28>
  VSS(77)  = GND
  DQ(24)  = M_K_DQ<24>
  VSS(76)  = GND
  DQS12P  = M_K_DQS_DP<12>
  DQS12N  = M_K_DQS_DN<12>
  VSS(75)  = GND
  DQ(30)  = M_K_DQ<30>
  VSS(74)  = GND
  DQ(26)  = M_K_DQ<26>
  VSS(73)  = GND
  CB(4)  = M_K_ECC<4>
  VSS(72)  = GND
  CB(0)  = M_K_ECC<0>
  VSS(71)  = GND
  DQS17P  = M_K_DQS_DP<17>
  DQS17N  = M_K_DQS_DN<17>
  VSS(70)  = GND
  CB(6)  = M_K_ECC<6>
  VSS(69)  = GND
  CB(2)  = M_K_ECC<2>
  VSS(68)  = GND
  RESET_N  = M_KLM_RST_N
  VDD(25)  = PVDDQ_KLM
  CKE(0)  = M_K_CKE<2>
  VDD(24)  = PVDDQ_KLM
  ACT_N  = M_K_ACT_N
  BG(0)  = M_K_BG<0>
  VDD(23)  = PVDDQ_KLM
  A12  = M_K_MA<12>
  A9  = M_K_MA<9>
  VDD(22)  = PVDDQ_KLM
  A8  = M_K_MA<8>
  A6  = M_K_MA<6>
  VDD(21)  = PVDDQ_KLM
  A3  = M_K_MA<3>
  A1  = M_K_MA<1>
  VDD(20)  = PVDDQ_KLM
  CK0P  = M_K_CLK_DP<2>
  CK0N  = M_K_CLK_DN<2>
  VDD(19)  = PVDDQ_KLM
  VTT(1)  = PVTT_KLM
  EVENT_N  = FM_DIMM_EVENT_COD_N
  A0  = M_K_MA<0>
  VDD(18)  = PVDDQ_KLM
  BA(0)  = M_K_BA<0>
  A16_RAS_N  = M_K_MA<16>
  VDD(17)  = PVDDQ_KLM
  S0_N  = M_K_CS_N<4>
  VDD(16)  = PVDDQ_KLM
  A15_CAS_N  = M_K_MA<15>
  ODT(0)  = M_K_ODT<2>
  VDD(15)  = PVDDQ_KLM
  S1_N  = M_K_CS_N<5>
  VDD(14)  = PVDDQ_KLM
  ODT(1)  = M_K_ODT<3>
  VDD(13)  = PVDDQ_KLM
  S2_N_C(0)  = M_K_CS_N<6>
  VSS(67)  = GND
  DQ(36)  = M_K_DQ<36>
  VSS(66)  = GND
  DQ(32)  = M_K_DQ<32>
  VSS(65)  = GND
  DQS13P  = M_K_DQS_DP<13>
  DQS13N  = M_K_DQS_DN<13>
  VSS(64)  = GND
  DQ(38)  = M_K_DQ<38>
  VSS(63)  = GND
  DQ(34)  = M_K_DQ<34>
  VSS(62)  = GND
  DQ(44)  = M_K_DQ<44>
  VSS(61)  = GND
  DQ(40)  = M_K_DQ<40>
  VSS(60)  = GND
  DQS14P  = M_K_DQS_DP<14>
  DQS14N  = M_K_DQS_DN<14>
  VSS(59)  = GND
  DQ(46)  = M_K_DQ<46>
  VSS(58)  = GND
  DQ(42)  = M_K_DQ<42>
  VSS(57)  = GND
  DQ(52)  = M_K_DQ<52>
  VSS(56)  = GND
  DQ(48)  = M_K_DQ<48>
  VSS(55)  = GND
  DQS15P  = M_K_DQS_DP<15>
  DQS15N  = M_K_DQS_DN<15>
  VSS(54)  = GND
  DQ(54)  = M_K_DQ<54>
  VSS(53)  = GND
  DQ(50)  = M_K_DQ<50>
  VSS(52)  = GND
  DQ(60)  = M_K_DQ<60>
  VSS(51)  = GND
  DQ(56)  = M_K_DQ<56>
  VSS(50)  = GND
  DQS16P  = M_K_DQS_DP<16>
  DQS16N  = M_K_DQS_DN<16>
  VSS(49)  = GND
  DQ(62)  = M_K_DQ<62>
  VSS(48)  = GND
  DQ(58)  = M_K_DQ<58>
  VSS(47)  = GND
  SA(0)  = PVPP_KLM
  SA(1)  = GND
  SCL  = SMB_DDR_KLM_VPP_SCL
  VPP(4)  = PVPP_KLM
  VPP(3)  = PVPP_KLM
  RFU(2)  = TP_CH_K_DIMM0_RFU_2
  \12v\(0)  = P12V_NVDIMM_KLM
  VREFCA  = M_K_VREF
  VSS(46)  = GND
  DQ(5)  = M_K_DQ<5>
  VSS(45)  = GND
  DQ(1)  = M_K_DQ<1>
  VSS(44)  = GND
  DQS0N  = M_K_DQS_DN<0>
  DQS0P  = M_K_DQS_DP<0>
  VSS(43)  = GND
  DQ(7)  = M_K_DQ<7>
  VSS(42)  = GND
  DQ(3)  = M_K_DQ<3>
  VSS(41)  = GND
  DQ(13)  = M_K_DQ<13>
  VSS(40)  = GND
  DQ(9)  = M_K_DQ<9>
  VSS(39)  = GND
  DQS1N  = M_K_DQS_DN<1>
  DQS1P  = M_K_DQS_DP<1>
  VSS(38)  = GND
  DQ(15)  = M_K_DQ<15>
  VSS(37)  = GND
  DQ(11)  = M_K_DQ<11>
  VSS(36)  = GND
  DQ(21)  = M_K_DQ<21>
  VSS(35)  = GND
  DQ(17)  = M_K_DQ<17>
  VSS(34)  = GND
  DQS2N  = M_K_DQS_DN<2>
  DQS2P  = M_K_DQS_DP<2>
  VSS(33)  = GND
  DQ(23)  = M_K_DQ<23>
  VSS(32)  = GND
  DQ(19)  = M_K_DQ<19>
  VSS(31)  = GND
  DQ(29)  = M_K_DQ<29>
  VSS(30)  = GND
  DQ(25)  = M_K_DQ<25>
  VSS(29)  = GND
  DQS3N  = M_K_DQS_DN<3>
  DQS3P  = M_K_DQS_DP<3>
  VSS(28)  = GND
  DQ(31)  = M_K_DQ<31>
  VSS(27)  = GND
  DQ(27)  = M_K_DQ<27>
  VSS(26)  = GND
  CB(5)  = M_K_ECC<5>
  VSS(25)  = GND
  CB(1)  = M_K_ECC<1>
  VSS(24)  = GND
  DQS8N  = M_K_DQS_DN<8>
  DQS8P  = M_K_DQS_DP<8>
  VSS(23)  = GND
  CB(7)  = M_K_ECC<7>
  VSS(22)  = GND
  CB(3)  = M_K_ECC<3>
  VSS(21)  = GND
  CKE(1)  = M_K_CKE<3>
  VDD(12)  = PVDDQ_KLM
  RFU(0)  = TP_CH_K_DIMM0_RFU_0
  VDD(11)  = PVDDQ_KLM
  BG(1)  = M_K_BG<1>
  ALERT_N  = M_K_ALERT_N
  VDD(10)  = PVDDQ_KLM
  A11  = M_K_MA<11>
  A7  = M_K_MA<7>
  VDD(9)  = PVDDQ_KLM
  A5  = M_K_MA<5>
  A4  = M_K_MA<4>
  VDD(8)  = PVDDQ_KLM
  A2  = M_K_MA<2>
  VDD(7)  = PVDDQ_KLM
  CK1P  = M_K_CLK_DP<3>
  CK1N  = M_K_CLK_DN<3>
  VDD(6)  = PVDDQ_KLM
  VTT(0)  = PVTT_KLM
  PAR  = M_K_PAR
  VDD(5)  = PVDDQ_KLM
  BA(1)  = M_K_BA<1>
  A10  = M_K_MA<10>
  VDD(4)  = PVDDQ_KLM
  RFU(1)  = TP_CH_K_DIMM0_RFU_1
  A14_WE_N  = M_K_MA<14>
  VDD(3)  = PVDDQ_KLM
  SAVE_N_NC  = FM_ADR_COMPLETE_KLM_N
  VDD(2)  = PVDDQ_KLM
  A13  = M_K_MA<13>
  VDD(1)  = PVDDQ_KLM
  A17  = M_K_MA<17>
  C(2)  = M_K_C<2>
  VDD(0)  = PVDDQ_KLM
  S3_N_C(1)  = M_K_CS_N<7>
  SA(2)  = GND
  VSS(20)  = GND
  DQ(37)  = M_K_DQ<37>
  VSS(19)  = GND
  DQ(33)  = M_K_DQ<33>
  VSS(18)  = GND
  DQS4N  = M_K_DQS_DN<4>
  DQS4P  = M_K_DQS_DP<4>
  VSS(17)  = GND
  DQ(39)  = M_K_DQ<39>
  VSS(16)  = GND
  DQ(35)  = M_K_DQ<35>
  VSS(15)  = GND
  DQ(45)  = M_K_DQ<45>
  VSS(14)  = GND
  DQ(41)  = M_K_DQ<41>
  VSS(13)  = GND
  DQS5N  = M_K_DQS_DN<5>
  DQS5P  = M_K_DQS_DP<5>
  VSS(12)  = GND
  DQ(47)  = M_K_DQ<47>
  VSS(11)  = GND
  DQ(43)  = M_K_DQ<43>
  VSS(10)  = GND
  DQ(53)  = M_K_DQ<53>
  VSS(9)  = GND
  DQ(49)  = M_K_DQ<49>
  VSS(8)  = GND
  DQS6N  = M_K_DQS_DN<6>
  DQS6P  = M_K_DQS_DP<6>
  VSS(7)  = GND
  DQ(55)  = M_K_DQ<55>
  VSS(6)  = GND
  DQ(51)  = M_K_DQ<51>
  VSS(5)  = GND
  DQ(61)  = M_K_DQ<61>
  VSS(4)  = GND
  DQ(57)  = M_K_DQ<57>
  VSS(3)  = GND
  DQS7N  = M_K_DQS_DN<7>
  DQS7P  = M_K_DQS_DP<7>
  VSS(2)  = GND
  DQ(63)  = M_K_DQ<63>
  VSS(1)  = GND
  DQ(59)  = M_K_DQ<59>
  VSS(0)  = GND
  VDDSPD  = PVPP_KLM
  SDA  = SMB_DDR_KLM_VPP_SDA
  VPP(1)  = PVPP_KLM
  VPP(0)  = PVPP_KLM
  VPP(2)  = PVPP_KLM

(kicad_pcb
	(version 20260206)
	(generator "pcbnew")
	(generator_version "10.0")
	(general
		(thickness 1.6)
		(legacy_teardrops no)
	)
	(paper "A4")
	(title_block
		(title "Wiwynn_Tioga_Pass_MB.brd")
		(comment 1 "Tioga Pass / footprint 2445 of 4770 (J9M1), pads 51-100 of 291")
	)
	(layers
		(0 "F.Cu" signal "TOP")
		(4 "In1.Cu" signal "L2GND")
		(6 "In2.Cu" signal "L3")
		(8 "In3.Cu" signal "L4GND")
		(10 "In4.Cu" signal "L5")
		(12 "In5.Cu" signal "L6GND")
		(14 "In6.Cu" signal "L7VCC")
		(16 "In7.Cu" signal "L8VCC")
		(18 "In8.Cu" signal "L9GND")
		(20 "In9.Cu" signal "L10")
		(22 "In10.Cu" signal "L11GND")
		(24 "In11.Cu" signal "L12")
		(26 "In12.Cu" signal "L13GND")
		(2 "B.Cu" signal "BOTTOM")
		(9 "F.Adhes" user "F.Adhesive")
		(11 "B.Adhes" user "B.Adhesive")
		(13 "F.Paste" user "Package Geometry/Pastemask Top")
		(15 "B.Paste" user "Package Geometry/Pastemask Bottom")
		(5 "F.SilkS" user "Ref Des/Silkscreen Top")
		(7 "B.SilkS" user "Ref Des/Silkscreen Bottom")
		(1 "F.Mask" user "Board Geometry/Soldermask Top")
		(3 "B.Mask" user "Board Geometry/Soldermask Bottom")
		(17 "Dwgs.User" user "User.Drawings")
		(19 "Cmts.User" user "User.Comments")
		(21 "Eco1.User" user "User.Eco1")
		(23 "Eco2.User" user "User.Eco2")
		(25 "Edge.Cuts" user "Board Geometry/Outline")
		(27 "Margin" user)
		(31 "F.CrtYd" user "Package Geometry/Place Bound Top")
		(29 "B.CrtYd" user "Package Geometry/Place Bound Bottom")
		(35 "F.Fab" user "Ref Des/Assembly Top")
		(33 "B.Fab" user "Ref Des/Assembly Bottom")
	)
	(footprint ""
		(layer "B.Cu")
		(at 29.699458 -132.876036 90)
		(property "Reference" "J9M1"
			(at 2.352548 37.991542 0)
			(unlocked yes)
			(layer "B.SilkS")
			(effects
				(font
					(size 0.7874 0.5842)
					(thickness 0.1524)
				)
				(justify left mirror)
			)
		)
		(property "Value" ""
			(at 0 0 90)
			(layer "B.Fab")
			(effects
				(font
					(size 1.27 1.27)
				)
				(justify mirror)
			)
		)
		(duplicate_pad_numbers_are_jumpers no)
		(pad "48" smd rect
			(at 0 39.949882 270)
			(size 1.8034 0.508)
			(layers "B.Cu" "B.Mask" "B.Paste")
			(net "GND")
		)
		(pad "49" smd rect
			(at 0 40.80002 270)
			(size 1.8034 0.508)
			(layers "B.Cu" "B.Mask" "B.Paste")
			(net "M_K_ECC<0>")
		)
		(pad "50" smd rect
			(at 0 41.649904 270)
			(size 1.8034 0.508)
			(layers "B.Cu" "B.Mask" "B.Paste")
			(net "GND")
		)
		(pad "51" smd rect
			(at 0 42.500042 270)
			(size 1.8034 0.508)
			(layers "B.Cu" "B.Mask" "B.Paste")
			(net "M_K_DQS_DP<17>")
		)
		(pad "52" smd rect
			(at 0 43.349926 270)
			(size 1.8034 0.508)
			(layers "B.Cu" "B.Mask" "B.Paste")
			(net "M_K_DQS_DN<17>")
		)
		(pad "53" smd rect
			(at 0 44.200064 270)
			(size 1.8034 0.508)
			(layers "B.Cu" "B.Mask" "B.Paste")
			(net "GND")
		)
		(pad "54" smd rect
			(at 0 45.049948 270)
			(size 1.8034 0.508)
			(layers "B.Cu" "B.Mask" "B.Paste")
			(net "M_K_ECC<6>")
		)
		(pad "55" smd rect
			(at 0 45.900086 270)
			(size 1.8034 0.508)
			(layers "B.Cu" "B.Mask" "B.Paste")
			(net "GND")
		)
		(pad "56" smd rect
			(at 0 46.74997 270)
			(size 1.8034 0.508)
			(layers "B.Cu" "B.Mask" "B.Paste")
			(net "M_K_ECC<2>")
		)
		(pad "57" smd rect
			(at 0 47.600108 270)
			(size 1.8034 0.508)
			(layers "B.Cu" "B.Mask" "B.Paste")
			(net "GND")
		)
		(pad "58" smd rect
			(at 0 48.449992 270)
			(size 1.8034 0.508)
			(layers "B.Cu" "B.Mask" "B.Paste")
			(net "M_KLM_RST_N")
		)
		(pad "59" smd rect
			(at 0 49.299876 270)
			(size 1.8034 0.508)
			(layers "B.Cu" "B.Mask" "B.Paste")
			(net "PVDDQ_KLM")
		)
		(pad "60" smd rect
			(at 0 50.150014 270)
			(size 1.8034 0.508)
			(layers "B.Cu" "B.Mask" "B.Paste")
			(net "M_K_CKE<2>")
		)
		(pad "61" smd rect
			(at 0 50.999898 270)
			(size 1.8034 0.508)
			(layers "B.Cu" "B.Mask" "B.Paste")
			(net "PVDDQ_KLM")
		)
		(pad "62" smd rect
			(at 0 51.850036 270)
			(size 1.8034 0.508)
			(layers "B.Cu" "B.Mask" "B.Paste")
			(net "M_K_ACT_N")
		)
		(pad "63" smd rect
			(at 0 52.69992 270)
			(size 1.8034 0.508)
			(layers "B.Cu" "B.Mask" "B.Paste")
			(net "M_K_BG<0>")
		)
		(pad "64" smd rect
			(at 0 53.550058 270)
			(size 1.8034 0.508)
			(layers "B.Cu" "B.Mask" "B.Paste")
			(net "PVDDQ_KLM")
		)
		(pad "65" smd rect
			(at 0 54.399942 270)
			(size 1.8034 0.508)
			(layers "B.Cu" "B.Mask" "B.Paste")
			(net "M_K_MA<12>")
		)
		(pad "66" smd rect
			(at 0 55.25008 270)
			(size 1.8034 0.508)
			(layers "B.Cu" "B.Mask" "B.Paste")
			(net "M_K_MA<9>")
		)
		(pad "67" smd rect
			(at 0 56.099964 270)
			(size 1.8034 0.508)
			(layers "B.Cu" "B.Mask" "B.Paste")
			(net "PVDDQ_KLM")
		)
		(pad "68" smd rect
			(at 0 56.950102 270)
			(size 1.8034 0.508)
			(layers "B.Cu" "B.Mask" "B.Paste")
			(net "M_K_MA<8>")
		)
		(pad "69" smd rect
			(at 0 57.799986 270)
			(size 1.8034 0.508)
			(layers "B.Cu" "B.Mask" "B.Paste")
			(net "M_K_MA<6>")
		)
		(pad "70" smd rect
			(at 0 58.650124 270)
			(size 1.8034 0.508)
			(layers "B.Cu" "B.Mask" "B.Paste")
			(net "PVDDQ_KLM")
		)
		(pad "71" smd rect
			(at 0 59.500008 270)
			(size 1.8034 0.508)
			(layers "B.Cu" "B.Mask" "B.Paste")
			(net "M_K_MA<3>")
		)
		(pad "72" smd rect
			(at 0 60.349892 270)
			(size 1.8034 0.508)
			(layers "B.Cu" "B.Mask" "B.Paste")
			(net "M_K_MA<1>")
		)
		(pad "73" smd rect
			(at 0 61.20003 270)
			(size 1.8034 0.508)
			(layers "B.Cu" "B.Mask" "B.Paste")
			(net "PVDDQ_KLM")
		)
		(pad "74" smd rect
			(at 0 62.049914 270)
			(size 1.8034 0.508)
			(layers "B.Cu" "B.Mask" "B.Paste")
			(net "M_K_CLK_DP<2>")
		)
		(pad "75" smd rect
			(at 0 62.900052 270)
			(size 1.8034 0.508)
			(layers "B.Cu" "B.Mask" "B.Paste")
			(net "M_K_CLK_DN<2>")
		)
		(pad "76" smd rect
			(at 0 63.749936 270)
			(size 1.8034 0.508)
			(layers "B.Cu" "B.Mask" "B.Paste")
			(net "PVDDQ_KLM")
		)
		(pad "77" smd rect
			(at 0 64.600074 270)
			(size 1.8034 0.508)
			(layers "B.Cu" "B.Mask" "B.Paste")
			(net "PVTT_KLM")
		)
		(pad "78" smd rect
			(at 0 70.550024 270)
			(size 1.8034 0.508)
			(layers "B.Cu" "B.Mask" "B.Paste")
			(net "FM_DIMM_EVENT_COD_N")
		)
		(pad "79" smd rect
			(at 0 71.399908 270)
			(size 1.8034 0.508)
			(layers "B.Cu" "B.Mask" "B.Paste")
			(net "M_K_MA<0>")
		)
		(pad "80" smd rect
			(at 0 72.250046 270)
			(size 1.8034 0.508)
			(layers "B.Cu" "B.Mask" "B.Paste")
			(net "PVDDQ_KLM")
		)
		(pad "81" smd rect
			(at 0 73.09993 270)
			(size 1.8034 0.508)
			(layers "B.Cu" "B.Mask" "B.Paste")
			(net "M_K_BA<0>")
		)
		(pad "82" smd rect
			(at 0 73.950068 270)
			(size 1.8034 0.508)
			(layers "B.Cu" "B.Mask" "B.Paste")
			(net "M_K_MA<16>")
		)
		(pad "83" smd rect
			(at 0 74.799952 270)
			(size 1.8034 0.508)
			(layers "B.Cu" "B.Mask" "B.Paste")
			(net "PVDDQ_KLM")
		)
		(pad "84" smd rect
			(at 0 75.65009 270)
			(size 1.8034 0.508)
			(layers "B.Cu" "B.Mask" "B.Paste")
			(net "M_K_CS_N<4>")
		)
		(pad "85" smd rect
			(at 0 76.499974 270)
			(size 1.8034 0.508)
			(layers "B.Cu" "B.Mask" "B.Paste")
			(net "PVDDQ_KLM")
		)
		(pad "86" smd rect
			(at 0 77.350112 270)
			(size 1.8034 0.508)
			(layers "B.Cu" "B.Mask" "B.Paste")
			(net "M_K_MA<15>")
		)
		(pad "87" smd rect
			(at 0 78.199996 270)
			(size 1.8034 0.508)
			(layers "B.Cu" "B.Mask" "B.Paste")
			(net "M_K_ODT<2>")
		)
		(pad "88" smd rect
			(at 0 79.04988 270)
			(size 1.8034 0.508)
			(layers "B.Cu" "B.Mask" "B.Paste")
			(net "PVDDQ_KLM")
		)
		(pad "89" smd rect
			(at 0 79.900018 270)
			(size 1.8034 0.508)
			(layers "B.Cu" "B.Mask" "B.Paste")
			(net "M_K_CS_N<5>")
		)
		(pad "90" smd rect
			(at 0 80.749902 270)
			(size 1.8034 0.508)
			(layers "B.Cu" "B.Mask" "B.Paste")
			(net "PVDDQ_KLM")
		)
		(pad "91" smd rect
			(at 0 81.60004 270)
			(size 1.8034 0.508)
			(layers "B.Cu" "B.Mask" "B.Paste")
			(net "M_K_ODT<3>")
		)
		(pad "92" smd rect
			(at 0 82.449924 270)
			(size 1.8034 0.508)
			(layers "B.Cu" "B.Mask" "B.Paste")
			(net "PVDDQ_KLM")
		)
		(pad "93" smd rect
			(at 0 83.300062 270)
			(size 1.8034 0.508)
			(layers "B.Cu" "B.Mask" "B.Paste")
			(net "M_K_CS_N<6>")
		)
		(pad "94" smd rect
			(at 0 84.149946 270)
			(size 1.8034 0.508)
			(layers "B.Cu" "B.Mask" "B.Paste")
			(net "GND")
		)
		(pad "95" smd rect
			(at 0 85.000084 270)
			(size 1.8034 0.508)
			(layers "B.Cu" "B.Mask" "B.Paste")
			(net "M_K_DQ<36>")
		)
		(pad "96" smd rect
			(at 0 85.849968 270)
			(size 1.8034 0.508)
			(layers "B.Cu" "B.Mask" "B.Paste")
			(net "GND")
		)
		(pad "97" smd rect
			(at 0 86.700106 270)
			(size 1.8034 0.508)
			(layers "B.Cu" "B.Mask" "B.Paste")
			(net "M_K_DQ<32>")
		)
	)
)
